(kicad_pcb
	(version 20260206)
	(generator "pcbnew")
	(generator_version "10.0")
	(general
		(thickness 1.6)
		(legacy_teardrops no)
	)
	(paper "A4")
	(title_block
		(title "04192023_DAF0TMB3IC0_F0TG_MB_C_brd_V02_OCP.brd")
		(comment 1 "Grand Teton / footprints 4789-4796 of 8354")
	)
	(layers
		(0 "F.Cu" signal "TOP")
		(4 "In1.Cu" signal "GND")
		(6 "In2.Cu" signal "IN1")
		(8 "In3.Cu" signal "GND1")
		(10 "In4.Cu" signal "IN2")
		(12 "In5.Cu" signal "GND2")
		(14 "In6.Cu" signal "IN3")
		(16 "In7.Cu" signal "GND3")
		(18 "In8.Cu" signal "VCC")
		(20 "In9.Cu" signal "VCC1")
		(22 "In10.Cu" signal "GND4")
		(24 "In11.Cu" signal "IN4")
		(26 "In12.Cu" signal "GND5")
		(28 "In13.Cu" signal "IN5")
		(30 "In14.Cu" signal "GND6")
		(32 "In15.Cu" signal "IN6")
		(34 "In16.Cu" signal "GND7")
		(2 "B.Cu" signal "BOTTOM")
		(9 "F.Adhes" user "F.Adhesive")
		(11 "B.Adhes" user "B.Adhesive")
		(13 "F.Paste" user "Package Geometry/Pastemask Top")
		(15 "B.Paste" user "Package Geometry/Pastemask Bottom")
		(5 "F.SilkS" user "Ref Des/Silkscreen Top")
		(7 "B.SilkS" user "Ref Des/Silkscreen Bottom")
		(1 "F.Mask" user "Board Geometry/Soldermask Top")
		(3 "B.Mask" user "Board Geometry/Soldermask Bottom")
		(17 "Dwgs.User" user "User.Drawings")
		(19 "Cmts.User" user "User.Comments")
		(21 "Eco1.User" user "User.Eco1")
		(23 "Eco2.User" user "User.Eco2")
		(25 "Edge.Cuts" user "Board Geometry/Outline")
		(27 "Margin" user)
		(31 "F.CrtYd" user "Package Geometry/Place Bound Top")
		(29 "B.CrtYd" user "Package Geometry/Place Bound Bottom")
		(35 "F.Fab" user "Ref Des/Assembly Top")
		(33 "B.Fab" user "Ref Des/Assembly Bottom")
	)
	(footprint ""
		(layer "F.Cu")
		(at 141.233652 -79.029052 90)
		(property "Reference" "PC6010"
			(at 0 0 90)
			(layer "F.SilkS")
			(hide yes)
			(effects
				(font
					(size 1.27 1.27)
				)
			)
		)
		(property "Value" ""
			(at 0 0 90)
			(layer "F.Fab")
			(effects
				(font
					(size 1.27 1.27)
				)
			)
		)
		(duplicate_pad_numbers_are_jumpers no)
		(fp_line
			(start 0.7874 -0.4064)
			(end 0.7874 0.4064)
			(stroke
				(width 0.1524)
				(type default)
			)
			(layer "F.SilkS")
		)
		(fp_line
			(start -0.7874 -0.4064)
			(end 0.7874 -0.4064)
			(stroke
				(width 0.1524)
				(type default)
			)
			(layer "F.SilkS")
		)
		(fp_line
			(start 0.7874 0.4064)
			(end -0.7874 0.4064)
			(stroke
				(width 0.1524)
				(type default)
			)
			(layer "F.SilkS")
		)
		(fp_line
			(start -0.7874 0.4064)
			(end -0.7874 -0.4064)
			(stroke
				(width 0.1524)
				(type default)
			)
			(layer "F.SilkS")
		)
		(fp_line
			(start -0.12065 -0.305054)
			(end -0.12065 -0.2794)
			(stroke
				(width 0.1)
				(type default)
			)
			(layer "F.Fab")
		)
		(fp_line
			(start -0.67945 -0.305054)
			(end -0.12065 -0.305054)
			(stroke
				(width 0.1)
				(type default)
			)
			(layer "F.Fab")
		)
		(fp_line
			(start 0.67945 -0.3048)
			(end 0.67945 0.3048)
			(stroke
				(width 0.1)
				(type default)
			)
			(layer "F.Fab")
		)
		(fp_line
			(start 0.12065 -0.3048)
			(end 0.67945 -0.3048)
			(stroke
				(width 0.1)
				(type default)
			)
			(layer "F.Fab")
		)
		(fp_line
			(start 0.12065 -0.2794)
			(end 0.12065 -0.3048)
			(stroke
				(width 0.1)
				(type default)
			)
			(layer "F.Fab")
		)
		(fp_line
			(start -0.12065 -0.2794)
			(end 0.12065 -0.2794)
			(stroke
				(width 0.1)
				(type default)
			)
			(layer "F.Fab")
		)
		(fp_line
			(start 0.120396 0.2794)
			(end -0.12065 0.2794)
			(stroke
				(width 0.1)
				(type default)
			)
			(layer "F.Fab")
		)
		(fp_line
			(start -0.12065 0.2794)
			(end -0.12065 0.3048)
			(stroke
				(width 0.1)
				(type default)
			)
			(layer "F.Fab")
		)
		(fp_line
			(start 0.67945 0.3048)
			(end 0.120396 0.3048)
			(stroke
				(width 0.1)
				(type default)
			)
			(layer "F.Fab")
		)
		(fp_line
			(start 0.120396 0.3048)
			(end 0.120396 0.2794)
			(stroke
				(width 0.1)
				(type default)
			)
			(layer "F.Fab")
		)
		(fp_line
			(start -0.12065 0.3048)
			(end -0.67945 0.3048)
			(stroke
				(width 0.1)
				(type default)
			)
			(layer "F.Fab")
		)
		(fp_line
			(start -0.67945 0.3048)
			(end -0.67945 -0.305054)
			(stroke
				(width 0.1)
				(type default)
			)
			(layer "F.Fab")
		)
		(pad "1" smd circle
			(at -0.40005 0 90)
			(size 0 0)
			(layers "F.Cu" "F.Mask" "F.Paste")
			(net "SW_P12V_AUX_P1V8_AUX_FLT")
		)
		(pad "2" smd circle
			(at 0.40005 0 90)
			(size 0 0)
			(layers "F.Cu" "F.Mask" "F.Paste")
			(net "GND")
		)
	)
	(footprint ""
		(layer "F.Cu")
		(at 140.661898 -160.403794 90)
		(property "Reference" "PL34"
			(at 3.955796 -3.199384 0)
			(unlocked yes)
			(layer "F.SilkS")
			(effects
				(font
					(size 0.7874 0.5842)
					(thickness 0.1524)
				)
				(justify left)
			)
		)
		(property "Value" ""
			(at 0 0 90)
			(layer "F.Fab")
			(effects
				(font
					(size 1.27 1.27)
				)
			)
		)
		(duplicate_pad_numbers_are_jumpers no)
		(fp_line
			(start 3.24993 -3.24993)
			(end 3.24993 -2.2352)
			(stroke
				(width 0.1524)
				(type default)
			)
			(layer "F.SilkS")
		)
		(fp_line
			(start -3.24993 -3.24993)
			(end 3.24993 -3.24993)
			(stroke
				(width 0.1524)
				(type default)
			)
			(layer "F.SilkS")
		)
		(fp_line
			(start -3.24993 -2.2352)
			(end -3.24993 -3.24993)
			(stroke
				(width 0.1524)
				(type default)
			)
			(layer "F.SilkS")
		)
		(fp_line
			(start 3.24993 2.2352)
			(end 3.24993 3.24993)
			(stroke
				(width 0.1524)
				(type default)
			)
			(layer "F.SilkS")
		)
		(fp_line
			(start 3.24993 3.24993)
			(end -3.24993 3.24993)
			(stroke
				(width 0.1524)
				(type default)
			)
			(layer "F.SilkS")
		)
		(fp_line
			(start -3.24993 3.24993)
			(end -3.24993 2.2352)
			(stroke
				(width 0.1524)
				(type default)
			)
			(layer "F.SilkS")
		)
		(fp_line
			(start 3.24993 -3.24993)
			(end 3.24993 3.24993)
			(stroke
				(width 0.1)
				(type default)
			)
			(layer "F.Fab")
		)
		(fp_line
			(start -3.24993 -3.24993)
			(end 3.24993 -3.24993)
			(stroke
				(width 0.1)
				(type default)
			)
			(layer "F.Fab")
		)
		(fp_line
			(start 3.24993 3.24993)
			(end -3.24993 3.24993)
			(stroke
				(width 0.1)
				(type default)
			)
			(layer "F.Fab")
		)
		(fp_line
			(start -3.24993 3.24993)
			(end -3.24993 -3.24993)
			(stroke
				(width 0.1)
				(type default)
			)
			(layer "F.Fab")
		)
		(pad "1" smd rect
			(at -2.29997 0 90)
			(size 2.0066 4.2164)
			(layers "F.Cu" "F.Mask" "F.Paste")
			(net "GND")
		)
		(pad "2" smd rect
			(at 2.29997 0 90)
			(size 2.0066 4.2164)
			(layers "F.Cu" "F.Mask" "F.Paste")
			(net "IND_SOC_P1_CPL0")
		)
	)
	(footprint ""
		(layer "F.Cu")
		(at 406.461976 -177.910998 180)
		(property "Reference" "PL64"
			(at -0.472694 5.858002 90)
			(unlocked yes)
			(layer "F.SilkS")
			(effects
				(font
					(size 0.7874 0.5842)
					(thickness 0.1524)
				)
				(justify left)
			)
		)
		(property "Value" ""
			(at 0 0 180)
			(layer "F.Fab")
			(effects
				(font
					(size 1.27 1.27)
				)
			)
		)
		(duplicate_pad_numbers_are_jumpers no)
		(fp_line
			(start 3.750056 5.500116)
			(end 3.750056 -5.500116)
			(stroke
				(width 0.1524)
				(type default)
			)
			(layer "F.SilkS")
		)
		(fp_line
			(start 3.750056 -5.500116)
			(end 2.393442 -5.500116)
			(stroke
				(width 0.1524)
				(type default)
			)
			(layer "F.SilkS")
		)
		(fp_line
			(start 2.393442 5.500116)
			(end 3.750056 5.500116)
			(stroke
				(width 0.1524)
				(type default)
			)
			(layer "F.SilkS")
		)
		(fp_line
			(start -2.393442 5.500116)
			(end -3.750056 5.500116)
			(stroke
				(width 0.1524)
				(type default)
			)
			(layer "F.SilkS")
		)
		(fp_line
			(start -3.750056 5.500116)
			(end -3.750056 -5.500116)
			(stroke
				(width 0.1524)
				(type default)
			)
			(layer "F.SilkS")
		)
		(fp_line
			(start -3.750056 -5.500116)
			(end -2.393442 -5.500116)
			(stroke
				(width 0.1524)
				(type default)
			)
			(layer "F.SilkS")
		)
		(fp_poly
			(pts
				(xy -3.9116 -4.249928) (xy -4.383024 -4.014216) (xy -4.383024 -4.48564)
			)
			(stroke
				(width 0)
				(type default)
			)
			(fill yes)
			(layer "F.SilkS")
		)
		(fp_line
			(start 3.750056 5.500116)
			(end 3.750056 -5.500116)
			(stroke
				(width 0.1)
				(type default)
			)
			(layer "F.Fab")
		)
		(fp_line
			(start 3.750056 -5.500116)
			(end -3.750056 -5.500116)
			(stroke
				(width 0.1)
				(type default)
			)
			(layer "F.Fab")
		)
		(fp_line
			(start -3.750056 5.500116)
			(end 3.750056 5.500116)
			(stroke
				(width 0.1)
				(type default)
			)
			(layer "F.Fab")
		)
		(fp_line
			(start -3.750056 -5.500116)
			(end -3.750056 5.500116)
			(stroke
				(width 0.1)
				(type default)
			)
			(layer "F.Fab")
		)
		(fp_poly
			(pts
				(xy -4.9276 -4.757928) (xy -4.9276 -3.741928) (xy -3.9116 -4.249928)
			)
			(stroke
				(width 0)
				(type default)
			)
			(fill yes)
			(layer "F.Fab")
		)
		(pad "1" smd rect
			(at 0 -4.249928 90)
			(size 2.413 4.5212)
			(layers "F.Cu" "F.Mask" "F.Paste")
			(net "SW_PVDDCR_SOC_P0_SW2")
		)
		(pad "2" smd rect
			(at 0 -1.175004 90)
			(size 1.3716 4.5212)
			(layers "F.Cu" "F.Mask" "F.Paste")
			(net "IND_SOC_P0_CPL3")
		)
		(pad "3" smd rect
			(at 0 1.175004 90)
			(size 1.3716 4.5212)
			(layers "F.Cu" "F.Mask" "F.Paste")
			(net "IND_SOC_P0_CPL2")
		)
		(pad "4" smd rect
			(at 0 4.249928 90)
			(size 2.413 4.5212)
			(layers "F.Cu" "F.Mask" "F.Paste")
			(net "PVDDCR_SOC_P0")
		)
	)
	(footprint ""
		(layer "F.Cu")
		(at 108.841794 -383.7432)
		(property "Reference" "R922"
			(at 0 0 0)
			(layer "F.SilkS")
			(hide yes)
			(effects
				(font
					(size 1.27 1.27)
				)
			)
		)
		(property "Value" ""
			(at 0 0 0)
			(layer "F.Fab")
			(effects
				(font
					(size 1.27 1.27)
				)
			)
		)
		(duplicate_pad_numbers_are_jumpers no)
		(fp_line
			(start -0.32512 -0.175006)
			(end 0.32512 -0.175006)
			(stroke
				(width 0.1)
				(type default)
			)
			(layer "F.Fab")
		)
		(fp_line
			(start -0.32512 0.175006)
			(end -0.32512 -0.175006)
			(stroke
				(width 0.1)
				(type default)
			)
			(layer "F.Fab")
		)
		(fp_line
			(start 0.32512 -0.175006)
			(end 0.32512 0.175006)
			(stroke
				(width 0.1)
				(type default)
			)
			(layer "F.Fab")
		)
		(fp_line
			(start 0.32512 0.175006)
			(end -0.32512 0.175006)
			(stroke
				(width 0.1)
				(type default)
			)
			(layer "F.Fab")
		)
		(pad "1" smd rect
			(at -0.2667 0)
			(size 0.3048 0.381)
			(layers "F.Cu" "F.Mask" "F.Paste")
			(net "P1V8_CPU1_RT_1D")
		)
		(pad "2" smd rect
			(at 0.2667 0 180)
			(size 0.3048 0.381)
			(layers "F.Cu" "F.Mask" "F.Paste")
			(net "TEST2_RT_CPU1_P3")
		)
	)
	(footprint ""
		(layer "F.Cu")
		(at 354.555044 -378.95403 -90)
		(property "Reference" "C940"
			(at 0 0 270)
			(layer "F.SilkS")
			(hide yes)
			(effects
				(font
					(size 1.27 1.27)
				)
			)
		)
		(property "Value" ""
			(at 0 0 270)
			(layer "F.Fab")
			(effects
				(font
					(size 1.27 1.27)
				)
			)
		)
		(duplicate_pad_numbers_are_jumpers no)
		(fp_line
			(start -0.299974 0.150114)
			(end -0.299974 -0.150114)
			(stroke
				(width 0.1)
				(type default)
			)
			(layer "F.Fab")
		)
		(fp_line
			(start 0.299974 0.150114)
			(end -0.299974 0.150114)
			(stroke
				(width 0.1)
				(type default)
			)
			(layer "F.Fab")
		)
		(fp_line
			(start -0.299974 -0.150114)
			(end 0.299974 -0.150114)
			(stroke
				(width 0.1)
				(type default)
			)
			(layer "F.Fab")
		)
		(fp_line
			(start 0.299974 -0.150114)
			(end 0.299974 0.150114)
			(stroke
				(width 0.1)
				(type default)
			)
			(layer "F.Fab")
		)
		(pad "1" smd rect
			(at -0.2667 0 270)
			(size 0.3048 0.381)
			(layers "F.Cu" "F.Mask" "F.Paste")
			(net "P5E_CPU0_P1_TX_C_DN<12>")
		)
		(pad "2" smd rect
			(at 0.2667 0 270)
			(size 0.3048 0.381)
			(layers "F.Cu" "F.Mask" "F.Paste")
			(net "P5E_CPU0_P1_TX_DN<12>")
		)
	)
	(footprint ""
		(layer "F.Cu")
		(at 413.14624 -381.41783 -90)
		(property "Reference" "C852"
			(at 0 0 270)
			(layer "F.SilkS")
			(hide yes)
			(effects
				(font
					(size 1.27 1.27)
				)
			)
		)
		(property "Value" ""
			(at 0 0 270)
			(layer "F.Fab")
			(effects
				(font
					(size 1.27 1.27)
				)
			)
		)
		(duplicate_pad_numbers_are_jumpers no)
		(fp_line
			(start -0.299974 0.150114)
			(end -0.299974 -0.150114)
			(stroke
				(width 0.1)
				(type default)
			)
			(layer "F.Fab")
		)
		(fp_line
			(start 0.299974 0.150114)
			(end -0.299974 0.150114)
			(stroke
				(width 0.1)
				(type default)
			)
			(layer "F.Fab")
		)
		(fp_line
			(start -0.299974 -0.150114)
			(end 0.299974 -0.150114)
			(stroke
				(width 0.1)
				(type default)
			)
			(layer "F.Fab")
		)
		(fp_line
			(start 0.299974 -0.150114)
			(end 0.299974 0.150114)
			(stroke
				(width 0.1)
				(type default)
			)
			(layer "F.Fab")
		)
		(pad "1" smd rect
			(at -0.2667 0 270)
			(size 0.3048 0.381)
			(layers "F.Cu" "F.Mask" "F.Paste")
			(net "P5E_CPU0_P2_TX_C_DN<8>")
		)
		(pad "2" smd rect
			(at 0.2667 0 270)
			(size 0.3048 0.381)
			(layers "F.Cu" "F.Mask" "F.Paste")
			(net "P5E_CPU0_P2_TX_DN<8>")
		)
	)
	(footprint ""
		(layer "F.Cu")
		(at 319.940178 -40.652954)
		(property "Reference" "C2050"
			(at 0 0 0)
			(layer "F.SilkS")
			(hide yes)
			(effects
				(font
					(size 1.27 1.27)
				)
			)
		)
		(property "Value" ""
			(at 0 0 0)
			(layer "F.Fab")
			(effects
				(font
					(size 1.27 1.27)
				)
			)
		)
		(duplicate_pad_numbers_are_jumpers no)
		(fp_line
			(start -0.7874 -0.4064)
			(end 0.7874 -0.4064)
			(stroke
				(width 0.1524)
				(type default)
			)
			(layer "F.SilkS")
		)
		(fp_line
			(start -0.7874 0.4064)
			(end -0.7874 -0.4064)
			(stroke
				(width 0.1524)
				(type default)
			)
			(layer "F.SilkS")
		)
		(fp_line
			(start 0.7874 -0.4064)
			(end 0.7874 0.4064)
			(stroke
				(width 0.1524)
				(type default)
			)
			(layer "F.SilkS")
		)
		(fp_line
			(start 0.7874 0.4064)
			(end -0.7874 0.4064)
			(stroke
				(width 0.1524)
				(type default)
			)
			(layer "F.SilkS")
		)
		(fp_line
			(start -0.67945 -0.305054)
			(end -0.12065 -0.305054)
			(stroke
				(width 0.1)
				(type default)
			)
			(layer "F.Fab")
		)
		(fp_line
			(start -0.67945 0.3048)
			(end -0.67945 -0.305054)
			(stroke
				(width 0.1)
				(type default)
			)
			(layer "F.Fab")
		)
		(fp_line
			(start -0.12065 -0.305054)
			(end -0.12065 -0.2794)
			(stroke
				(width 0.1)
				(type default)
			)
			(layer "F.Fab")
		)
		(fp_line
			(start -0.12065 -0.2794)
			(end 0.12065 -0.2794)
			(stroke
				(width 0.1)
				(type default)
			)
			(layer "F.Fab")
		)
		(fp_line
			(start -0.12065 0.2794)
			(end -0.12065 0.3048)
			(stroke
				(width 0.1)
				(type default)
			)
			(layer "F.Fab")
		)
		(fp_line
			(start -0.12065 0.3048)
			(end -0.67945 0.3048)
			(stroke
				(width 0.1)
				(type default)
			)
			(layer "F.Fab")
		)
		(fp_line
			(start 0.120396 0.2794)
			(end -0.12065 0.2794)
			(stroke
				(width 0.1)
				(type default)
			)
			(layer "F.Fab")
		)
		(fp_line
			(start 0.120396 0.3048)
			(end 0.120396 0.2794)
			(stroke
				(width 0.1)
				(type default)
			)
			(layer "F.Fab")
		)
		(fp_line
			(start 0.12065 -0.3048)
			(end 0.67945 -0.3048)
			(stroke
				(width 0.1)
				(type default)
			)
			(layer "F.Fab")
		)
		(fp_line
			(start 0.12065 -0.2794)
			(end 0.12065 -0.3048)
			(stroke
				(width 0.1)
				(type default)
			)
			(layer "F.Fab")
		)
		(fp_line
			(start 0.67945 -0.3048)
			(end 0.67945 0.3048)
			(stroke
				(width 0.1)
				(type default)
			)
			(layer "F.Fab")
		)
		(fp_line
			(start 0.67945 0.3048)
			(end 0.120396 0.3048)
			(stroke
				(width 0.1)
				(type default)
			)
			(layer "F.Fab")
		)
		(pad "1" smd circle
			(at -0.40005 0)
			(size 0 0)
			(layers "F.Cu" "F.Mask" "F.Paste")
			(net "P3V3_PDB_AUX_ADC_TIC")
		)
		(pad "2" smd circle
			(at 0.40005 0)
			(size 0 0)
			(layers "F.Cu" "F.Mask" "F.Paste")
			(net "GND")
		)
	)
	(footprint ""
		(layer "F.Cu")
		(at 161.097976 -129.295652 -90)
		(property "Reference" "R552"
			(at 0 0 270)
			(layer "F.SilkS")
			(hide yes)
			(effects
				(font
					(size 1.27 1.27)
				)
			)
		)
		(property "Value" ""
			(at 0 0 270)
			(layer "F.Fab")
			(effects
				(font
					(size 1.27 1.27)
				)
			)
		)
		(duplicate_pad_numbers_are_jumpers no)
		(fp_line
			(start -0.7874 0.4064)
			(end -0.7874 -0.4064)
			(stroke
				(width 0.1524)
				(type default)
			)
			(layer "F.SilkS")
		)
		(fp_line
			(start 0.7874 0.4064)
			(end -0.7874 0.4064)
			(stroke
				(width 0.1524)
				(type default)
			)
			(layer "F.SilkS")
		)
		(fp_line
			(start -0.7874 -0.4064)
			(end 0.7874 -0.4064)
			(stroke
				(width 0.1524)
				(type default)
			)
			(layer "F.SilkS")
		)
		(fp_line
			(start 0.7874 -0.4064)
			(end 0.7874 0.4064)
			(stroke
				(width 0.1524)
				(type default)
			)
			(layer "F.SilkS")
		)
		(fp_line
			(start -0.67945 0.3048)
			(end -0.67945 -0.305054)
			(stroke
				(width 0.1)
				(type default)
			)
			(layer "F.Fab")
		)
		(fp_line
			(start -0.12065 0.3048)
			(end -0.67945 0.3048)
			(stroke
				(width 0.1)
				(type default)
			)
			(layer "F.Fab")
		)
		(fp_line
			(start 0.120396 0.3048)
			(end 0.120396 0.2794)
			(stroke
				(width 0.1)
				(type default)
			)
			(layer "F.Fab")
		)
		(fp_line
			(start 0.67945 0.3048)
			(end 0.120396 0.3048)
			(stroke
				(width 0.1)
				(type default)
			)
			(layer "F.Fab")
		)
		(fp_line
			(start -0.12065 0.2794)
			(end -0.12065 0.3048)
			(stroke
				(width 0.1)
				(type default)
			)
			(layer "F.Fab")
		)
		(fp_line
			(start 0.120396 0.2794)
			(end -0.12065 0.2794)
			(stroke
				(width 0.1)
				(type default)
			)
			(layer "F.Fab")
		)
		(fp_line
			(start -0.12065 -0.2794)
			(end 0.12065 -0.2794)
			(stroke
				(width 0.1)
				(type default)
			)
			(layer "F.Fab")
		)
		(fp_line
			(start 0.12065 -0.2794)
			(end 0.12065 -0.3048)
			(stroke
				(width 0.1)
				(type default)
			)
			(layer "F.Fab")
		)
		(fp_line
			(start 0.12065 -0.3048)
			(end 0.67945 -0.3048)
			(stroke
				(width 0.1)
				(type default)
			)
			(layer "F.Fab")
		)
		(fp_line
			(start 0.67945 -0.3048)
			(end 0.67945 0.3048)
			(stroke
				(width 0.1)
				(type default)
			)
			(layer "F.Fab")
		)
		(fp_line
			(start -0.67945 -0.305054)
			(end -0.12065 -0.305054)
			(stroke
				(width 0.1)
				(type default)
			)
			(layer "F.Fab")
		)
		(fp_line
			(start -0.12065 -0.305054)
			(end -0.12065 -0.2794)
			(stroke
				(width 0.1)
				(type default)
			)
			(layer "F.Fab")
		)
		(pad "1" smd circle
			(at -0.40005 0 270)
			(size 0 0)
			(layers "F.Cu" "F.Mask" "F.Paste")
			(net "P3V3_AUX")
		)
		(pad "2" smd circle
			(at 0.40005 0 270)
			(size 0 0)
			(layers "F.Cu" "F.Mask" "F.Paste")
			(net "PWRGD_P5V_R2")
		)
	)
)
